# ZAIUS-LBB-EVT2-X01-BOM-X03-20161116.xls — DEPOP (bom)
| FOXCONN TECHNOLOGY GROUP |  |  |  |  |  |  |  |  |  |  |  |  |
| BILL OF MATERIAL |  |  |  |  |  |  |  |  |  |  |  |  |
| REV OF  BOM |  | CUSTOMER | DELL |  | CUSTOMER P/N |  | PRODUCT CODE |  | PWA  REV |  | DATE |  |
| Sourcing (Single/Sole/Multi) | Critical Commodity (Y or N) | Component Class (1, 2, other) | Dell PSL (Y or N) | Item Number | Foxconn P/N | Dell P/N | Part Description | Manufacturer  Full Name | Manufacturer  Part Number | Qty | RoHS Status | Location |
